# T6G (Grand Teton) — schematic netlist excerpt (pin names and nets, part order shuffled) for the footprints in the layout excerpt that follows; sources: Cadence DE-HDL packaged netlist, KiCad conversion of 04192023_DAF0TMB3IC0_F0TG_MB_C_brd_V02_OCP.brd

R2668  Q_RES  4.7K 5% EMPTY  pkg 0402LF  page 248 : A = P3V3_AUX ; B = I3C_BMC_SWB_BUF_R_SDA
R1687  Q_RES  10 1% CHIP  pkg 0402LF  page 98 : A = I3C_SPD_DDRAF_CPU1_SDA ; B = I3C_SPD_DDRA_CPU1_SDA

(kicad_pcb
	(version 20260206)
	(generator "pcbnew")
	(generator_version "10.0")
	(general
		(thickness 1.6)
		(legacy_teardrops no)
	)
	(paper "A4")
	(title_block
		(title "04192023_DAF0TMB3IC0_F0TG_MB_C_brd_V02_OCP.brd")
		(comment 1 "Grand Teton / footprints 7652-7653 of 8354")
	)
	(layers
		(0 "F.Cu" signal "TOP")
		(4 "In1.Cu" signal "GND")
		(6 "In2.Cu" signal "IN1")
		(8 "In3.Cu" signal "GND1")
		(10 "In4.Cu" signal "IN2")
		(12 "In5.Cu" signal "GND2")
		(14 "In6.Cu" signal "IN3")
		(16 "In7.Cu" signal "GND3")
		(18 "In8.Cu" signal "VCC")
		(20 "In9.Cu" signal "VCC1")
		(22 "In10.Cu" signal "GND4")
		(24 "In11.Cu" signal "IN4")
		(26 "In12.Cu" signal "GND5")
		(28 "In13.Cu" signal "IN5")
		(30 "In14.Cu" signal "GND6")
		(32 "In15.Cu" signal "IN6")
		(34 "In16.Cu" signal "GND7")
		(2 "B.Cu" signal "BOTTOM")
		(9 "F.Adhes" user "F.Adhesive")
		(11 "B.Adhes" user "B.Adhesive")
		(13 "F.Paste" user "Package Geometry/Pastemask Top")
		(15 "B.Paste" user "Package Geometry/Pastemask Bottom")
		(5 "F.SilkS" user "Ref Des/Silkscreen Top")
		(7 "B.SilkS" user "Ref Des/Silkscreen Bottom")
		(1 "F.Mask" user "Board Geometry/Soldermask Top")
		(3 "B.Mask" user "Board Geometry/Soldermask Bottom")
		(17 "Dwgs.User" user "User.Drawings")
		(19 "Cmts.User" user "User.Comments")
		(21 "Eco1.User" user "User.Eco1")
		(23 "Eco2.User" user "User.Eco2")
		(25 "Edge.Cuts" user "Board Geometry/Outline")
		(27 "Margin" user)
		(31 "F.CrtYd" user "Package Geometry/Place Bound Top")
		(29 "B.CrtYd" user "Package Geometry/Place Bound Bottom")
		(35 "F.Fab" user "Ref Des/Assembly Top")
		(33 "B.Fab" user "Ref Des/Assembly Bottom")
	)
	(footprint ""
		(layer "B.Cu")
		(at 292.608 -426.085 -90)
		(property "Reference" "R2668"
			(at 0 0 90)
			(layer "B.SilkS")
			(hide yes)
			(effects
				(font
					(size 1.27 1.27)
				)
				(justify mirror)
			)
		)
		(property "Value" ""
			(at 0 0 90)
			(layer "B.Fab")
			(effects
				(font
					(size 1.27 1.27)
				)
				(justify mirror)
			)
		)
		(duplicate_pad_numbers_are_jumpers no)
		(fp_line
			(start -0.7874 0.4064)
			(end 0.7874 0.4064)
			(stroke
				(width 0.1524)
				(type default)
			)
			(layer "B.SilkS")
		)
		(fp_line
			(start 0.7874 0.4064)
			(end 0.7874 -0.4064)
			(stroke
				(width 0.1524)
				(type default)
			)
			(layer "B.SilkS")
		)
		(fp_line
			(start -0.7874 -0.4064)
			(end -0.7874 0.4064)
			(stroke
				(width 0.1524)
				(type default)
			)
			(layer "B.SilkS")
		)
		(fp_line
			(start 0.7874 -0.4064)
			(end -0.7874 -0.4064)
			(stroke
				(width 0.1524)
				(type default)
			)
			(layer "B.SilkS")
		)
		(fp_line
			(start -0.67945 0.3048)
			(end -0.120396 0.3048)
			(stroke
				(width 0.1)
				(type default)
			)
			(layer "B.Fab")
		)
		(fp_line
			(start -0.120396 0.3048)
			(end -0.120396 0.2794)
			(stroke
				(width 0.1)
				(type default)
			)
			(layer "B.Fab")
		)
		(fp_line
			(start 0.12065 0.3048)
			(end 0.67945 0.3048)
			(stroke
				(width 0.1)
				(type default)
			)
			(layer "B.Fab")
		)
		(fp_line
			(start 0.67945 0.3048)
			(end 0.67945 -0.305054)
			(stroke
				(width 0.1)
				(type default)
			)
			(layer "B.Fab")
		)
		(fp_line
			(start -0.120396 0.2794)
			(end 0.12065 0.2794)
			(stroke
				(width 0.1)
				(type default)
			)
			(layer "B.Fab")
		)
		(fp_line
			(start 0.12065 0.2794)
			(end 0.12065 0.3048)
			(stroke
				(width 0.1)
				(type default)
			)
			(layer "B.Fab")
		)
		(fp_line
			(start -0.12065 -0.2794)
			(end -0.12065 -0.3048)
			(stroke
				(width 0.1)
				(type default)
			)
			(layer "B.Fab")
		)
		(fp_line
			(start 0.12065 -0.2794)
			(end -0.12065 -0.2794)
			(stroke
				(width 0.1)
				(type default)
			)
			(layer "B.Fab")
		)
		(fp_line
			(start -0.67945 -0.3048)
			(end -0.67945 0.3048)
			(stroke
				(width 0.1)
				(type default)
			)
			(layer "B.Fab")
		)
		(fp_line
			(start -0.12065 -0.3048)
			(end -0.67945 -0.3048)
			(stroke
				(width 0.1)
				(type default)
			)
			(layer "B.Fab")
		)
		(fp_line
			(start 0.12065 -0.305054)
			(end 0.12065 -0.2794)
			(stroke
				(width 0.1)
				(type default)
			)
			(layer "B.Fab")
		)
		(fp_line
			(start 0.67945 -0.305054)
			(end 0.12065 -0.305054)
			(stroke
				(width 0.1)
				(type default)
			)
			(layer "B.Fab")
		)
		(pad "1" smd circle
			(at 0.40005 0 90)
			(size 0 0)
			(layers "B.Cu" "B.Mask" "B.Paste")
			(net "P3V3_AUX")
		)
		(pad "2" smd circle
			(at -0.40005 0 90)
			(size 0 0)
			(layers "B.Cu" "B.Mask" "B.Paste")
			(net "I3C_BMC_SWB_BUF_R_SDA")
		)
	)
	(footprint ""
		(layer "B.Cu")
		(at 59.401202 -195.926964 180)
		(property "Reference" "R1687"
			(at 0 0 0)
			(layer "B.SilkS")
			(hide yes)
			(effects
				(font
					(size 1.27 1.27)
				)
				(justify mirror)
			)
		)
		(property "Value" ""
			(at 0 0 0)
			(layer "B.Fab")
			(effects
				(font
					(size 1.27 1.27)
				)
				(justify mirror)
			)
		)
		(duplicate_pad_numbers_are_jumpers no)
		(fp_line
			(start 0.7874 0.4064)
			(end 0.7874 -0.4064)
			(stroke
				(width 0.1524)
				(type default)
			)
			(layer "B.SilkS")
		)
		(fp_line
			(start 0.7874 -0.4064)
			(end -0.7874 -0.4064)
			(stroke
				(width 0.1524)
				(type default)
			)
			(layer "B.SilkS")
		)
		(fp_line
			(start -0.7874 0.4064)
			(end 0.7874 0.4064)
			(stroke
				(width 0.1524)
				(type default)
			)
			(layer "B.SilkS")
		)
		(fp_line
			(start -0.7874 -0.4064)
			(end -0.7874 0.4064)
			(stroke
				(width 0.1524)
				(type default)
			)
			(layer "B.SilkS")
		)
		(fp_line
			(start 0.67945 0.3048)
			(end 0.67945 -0.305054)
			(stroke
				(width 0.1)
				(type default)
			)
			(layer "B.Fab")
		)
		(fp_line
			(start 0.67945 -0.305054)
			(end 0.12065 -0.305054)
			(stroke
				(width 0.1)
				(type default)
			)
			(layer "B.Fab")
		)
		(fp_line
			(start 0.12065 0.3048)
			(end 0.67945 0.3048)
			(stroke
				(width 0.1)
				(type default)
			)
			(layer "B.Fab")
		)
		(fp_line
			(start 0.12065 0.2794)
			(end 0.12065 0.3048)
			(stroke
				(width 0.1)
				(type default)
			)
			(layer "B.Fab")
		)
		(fp_line
			(start 0.12065 -0.2794)
			(end -0.12065 -0.2794)
			(stroke
				(width 0.1)
				(type default)
			)
			(layer "B.Fab")
		)
		(fp_line
			(start 0.12065 -0.305054)
			(end 0.12065 -0.2794)
			(stroke
				(width 0.1)
				(type default)
			)
			(layer "B.Fab")
		)
		(fp_line
			(start -0.120396 0.3048)
			(end -0.120396 0.2794)
			(stroke
				(width 0.1)
				(type default)
			)
			(layer "B.Fab")
		)
		(fp_line
			(start -0.120396 0.2794)
			(end 0.12065 0.2794)
			(stroke
				(width 0.1)
				(type default)
			)
			(layer "B.Fab")
		)
		(fp_line
			(start -0.12065 -0.2794)
			(end -0.12065 -0.3048)
			(stroke
				(width 0.1)
				(type default)
			)
			(layer "B.Fab")
		)
		(fp_line
			(start -0.12065 -0.3048)
			(end -0.67945 -0.3048)
			(stroke
				(width 0.1)
				(type default)
			)
			(layer "B.Fab")
		)
		(fp_line
			(start -0.67945 0.3048)
			(end -0.120396 0.3048)
			(stroke
				(width 0.1)
				(type default)
			)
			(layer "B.Fab")
		)
		(fp_line
			(start -0.67945 -0.3048)
			(end -0.67945 0.3048)
			(stroke
				(width 0.1)
				(type default)
			)
			(layer "B.Fab")
		)
		(pad "1" smd circle
			(at 0.40005 0)
			(size 0 0)
			(layers "B.Cu" "B.Mask" "B.Paste")
			(net "I3C_SPD_DDRAF_CPU1_SDA")
		)
		(pad "2" smd circle
			(at -0.40005 0)
			(size 0 0)
			(layers "B.Cu" "B.Mask" "B.Paste")
			(net "I3C_SPD_DDRA_CPU1_SDA")
		)
	)
)
